# T6G (Grand Teton) — schematic netlist excerpt (pin names and nets, part order shuffled) for the footprints in the layout excerpt that follows; sources: Cadence DE-HDL packaged netlist, KiCad conversion of 04192023_DAF0TMB3IC0_F0TG_MB_C_brd_V02_OCP.brd

C1921  Q_CAP  22UF 6.3V 20% X6S  pkg C0603  page 144 : A = P3V3_M2_0 ; B = GND
R1481  Q_RES  10 1% EMPTY  pkg 2512LF  page 169 : A = P3V3_AUX ; B = P3V3_AUX_DSC
R3799  Q_RES  100K 1% CHIP  pkg 0402LF  page 134 : A = P3V3_AUX ; B = P12V_OCP_FAULT_1

(kicad_pcb
	(version 20260206)
	(generator "pcbnew")
	(generator_version "10.0")
	(general
		(thickness 1.6)
		(legacy_teardrops no)
	)
	(paper "A4")
	(title_block
		(title "04192023_DAF0TMB3IC0_F0TG_MB_C_brd_V02_OCP.brd")
		(comment 1 "Grand Teton / footprints 1487-1489 of 8354")
	)
	(layers
		(0 "F.Cu" signal "TOP")
		(4 "In1.Cu" signal "GND")
		(6 "In2.Cu" signal "IN1")
		(8 "In3.Cu" signal "GND1")
		(10 "In4.Cu" signal "IN2")
		(12 "In5.Cu" signal "GND2")
		(14 "In6.Cu" signal "IN3")
		(16 "In7.Cu" signal "GND3")
		(18 "In8.Cu" signal "VCC")
		(20 "In9.Cu" signal "VCC1")
		(22 "In10.Cu" signal "GND4")
		(24 "In11.Cu" signal "IN4")
		(26 "In12.Cu" signal "GND5")
		(28 "In13.Cu" signal "IN5")
		(30 "In14.Cu" signal "GND6")
		(32 "In15.Cu" signal "IN6")
		(34 "In16.Cu" signal "GND7")
		(2 "B.Cu" signal "BOTTOM")
		(9 "F.Adhes" user "F.Adhesive")
		(11 "B.Adhes" user "B.Adhesive")
		(13 "F.Paste" user "Package Geometry/Pastemask Top")
		(15 "B.Paste" user "Package Geometry/Pastemask Bottom")
		(5 "F.SilkS" user "Ref Des/Silkscreen Top")
		(7 "B.SilkS" user "Ref Des/Silkscreen Bottom")
		(1 "F.Mask" user "Board Geometry/Soldermask Top")
		(3 "B.Mask" user "Board Geometry/Soldermask Bottom")
		(17 "Dwgs.User" user "User.Drawings")
		(19 "Cmts.User" user "User.Comments")
		(21 "Eco1.User" user "User.Eco1")
		(23 "Eco2.User" user "User.Eco2")
		(25 "Edge.Cuts" user "Board Geometry/Outline")
		(27 "Margin" user)
		(31 "F.CrtYd" user "Package Geometry/Place Bound Top")
		(29 "B.CrtYd" user "Package Geometry/Place Bound Bottom")
		(35 "F.Fab" user "Ref Des/Assembly Top")
		(33 "B.Fab" user "Ref Des/Assembly Bottom")
	)
	(footprint ""
		(layer "F.Cu")
		(at 454.847452 -21.302218 90)
		(property "Reference" "R3799"
			(at 0 0 90)
			(layer "F.SilkS")
			(hide yes)
			(effects
				(font
					(size 1.27 1.27)
				)
			)
		)
		(property "Value" ""
			(at 0 0 90)
			(layer "F.Fab")
			(effects
				(font
					(size 1.27 1.27)
				)
			)
		)
		(duplicate_pad_numbers_are_jumpers no)
		(fp_line
			(start 0.7874 -0.4064)
			(end 0.7874 0.4064)
			(stroke
				(width 0.1524)
				(type default)
			)
			(layer "F.SilkS")
		)
		(fp_line
			(start -0.7874 -0.4064)
			(end 0.7874 -0.4064)
			(stroke
				(width 0.1524)
				(type default)
			)
			(layer "F.SilkS")
		)
		(fp_line
			(start 0.7874 0.4064)
			(end -0.7874 0.4064)
			(stroke
				(width 0.1524)
				(type default)
			)
			(layer "F.SilkS")
		)
		(fp_line
			(start -0.7874 0.4064)
			(end -0.7874 -0.4064)
			(stroke
				(width 0.1524)
				(type default)
			)
			(layer "F.SilkS")
		)
		(fp_line
			(start -0.12065 -0.305054)
			(end -0.12065 -0.2794)
			(stroke
				(width 0.1)
				(type default)
			)
			(layer "F.Fab")
		)
		(fp_line
			(start -0.67945 -0.305054)
			(end -0.12065 -0.305054)
			(stroke
				(width 0.1)
				(type default)
			)
			(layer "F.Fab")
		)
		(fp_line
			(start 0.67945 -0.3048)
			(end 0.67945 0.3048)
			(stroke
				(width 0.1)
				(type default)
			)
			(layer "F.Fab")
		)
		(fp_line
			(start 0.12065 -0.3048)
			(end 0.67945 -0.3048)
			(stroke
				(width 0.1)
				(type default)
			)
			(layer "F.Fab")
		)
		(fp_line
			(start 0.12065 -0.2794)
			(end 0.12065 -0.3048)
			(stroke
				(width 0.1)
				(type default)
			)
			(layer "F.Fab")
		)
		(fp_line
			(start -0.12065 -0.2794)
			(end 0.12065 -0.2794)
			(stroke
				(width 0.1)
				(type default)
			)
			(layer "F.Fab")
		)
		(fp_line
			(start 0.120396 0.2794)
			(end -0.12065 0.2794)
			(stroke
				(width 0.1)
				(type default)
			)
			(layer "F.Fab")
		)
		(fp_line
			(start -0.12065 0.2794)
			(end -0.12065 0.3048)
			(stroke
				(width 0.1)
				(type default)
			)
			(layer "F.Fab")
		)
		(fp_line
			(start 0.67945 0.3048)
			(end 0.120396 0.3048)
			(stroke
				(width 0.1)
				(type default)
			)
			(layer "F.Fab")
		)
		(fp_line
			(start 0.120396 0.3048)
			(end 0.120396 0.2794)
			(stroke
				(width 0.1)
				(type default)
			)
			(layer "F.Fab")
		)
		(fp_line
			(start -0.12065 0.3048)
			(end -0.67945 0.3048)
			(stroke
				(width 0.1)
				(type default)
			)
			(layer "F.Fab")
		)
		(fp_line
			(start -0.67945 0.3048)
			(end -0.67945 -0.305054)
			(stroke
				(width 0.1)
				(type default)
			)
			(layer "F.Fab")
		)
		(pad "1" smd circle
			(at -0.40005 0 90)
			(size 0 0)
			(layers "F.Cu" "F.Mask" "F.Paste")
			(net "P3V3_AUX")
		)
		(pad "2" smd circle
			(at 0.40005 0 90)
			(size 0 0)
			(layers "F.Cu" "F.Mask" "F.Paste")
			(net "P12V_OCP_FAULT_1")
		)
	)
	(footprint ""
		(layer "F.Cu")
		(at 164.128704 -51.81473 -90)
		(property "Reference" "C1921"
			(at 0 0 270)
			(layer "F.SilkS")
			(hide yes)
			(effects
				(font
					(size 1.27 1.27)
				)
			)
		)
		(property "Value" ""
			(at 0 0 270)
			(layer "F.Fab")
			(effects
				(font
					(size 1.27 1.27)
				)
			)
		)
		(duplicate_pad_numbers_are_jumpers no)
		(fp_line
			(start -1.2954 0.5842)
			(end -1.2954 -0.5842)
			(stroke
				(width 0.1524)
				(type default)
			)
			(layer "F.SilkS")
		)
		(fp_line
			(start 1.2954 0.5842)
			(end -1.2954 0.5842)
			(stroke
				(width 0.1524)
				(type default)
			)
			(layer "F.SilkS")
		)
		(fp_line
			(start -1.2954 -0.5842)
			(end 1.2954 -0.5842)
			(stroke
				(width 0.1524)
				(type default)
			)
			(layer "F.SilkS")
		)
		(fp_line
			(start 1.2954 -0.5842)
			(end 1.2954 0.5842)
			(stroke
				(width 0.1524)
				(type default)
			)
			(layer "F.SilkS")
		)
		(fp_line
			(start -0.8636 0.4572)
			(end -0.8636 0.4064)
			(stroke
				(width 0.1)
				(type default)
			)
			(layer "F.Fab")
		)
		(fp_line
			(start 0.8636 0.4572)
			(end -0.8636 0.4572)
			(stroke
				(width 0.1)
				(type default)
			)
			(layer "F.Fab")
		)
		(fp_line
			(start -1.1938 0.4064)
			(end -1.1938 -0.4064)
			(stroke
				(width 0.1)
				(type default)
			)
			(layer "F.Fab")
		)
		(fp_line
			(start -0.8636 0.4064)
			(end -1.1938 0.4064)
			(stroke
				(width 0.1)
				(type default)
			)
			(layer "F.Fab")
		)
		(fp_line
			(start 0.8636 0.4064)
			(end 0.8636 0.4572)
			(stroke
				(width 0.1)
				(type default)
			)
			(layer "F.Fab")
		)
		(fp_line
			(start 1.1938 0.4064)
			(end 0.8636 0.4064)
			(stroke
				(width 0.1)
				(type default)
			)
			(layer "F.Fab")
		)
		(fp_line
			(start -1.1938 -0.4064)
			(end -0.8636 -0.4064)
			(stroke
				(width 0.1)
				(type default)
			)
			(layer "F.Fab")
		)
		(fp_line
			(start -0.8636 -0.4064)
			(end -0.8636 -0.4572)
			(stroke
				(width 0.1)
				(type default)
			)
			(layer "F.Fab")
		)
		(fp_line
			(start 0.8636 -0.4064)
			(end 1.1938 -0.4064)
			(stroke
				(width 0.1)
				(type default)
			)
			(layer "F.Fab")
		)
		(fp_line
			(start 1.1938 -0.4064)
			(end 1.1938 0.4064)
			(stroke
				(width 0.1)
				(type default)
			)
			(layer "F.Fab")
		)
		(fp_line
			(start -0.8636 -0.4572)
			(end 0.8636 -0.4572)
			(stroke
				(width 0.1)
				(type default)
			)
			(layer "F.Fab")
		)
		(fp_line
			(start 0.8636 -0.4572)
			(end 0.8636 -0.4064)
			(stroke
				(width 0.1)
				(type default)
			)
			(layer "F.Fab")
		)
		(pad "1" smd rect
			(at -0.7366 0 180)
			(size 0.7112 0.8128)
			(layers "F.Cu" "F.Mask" "F.Paste")
			(net "P3V3_M2_0")
		)
		(pad "2" smd rect
			(at 0.7366 0 180)
			(size 0.7112 0.8128)
			(layers "F.Cu" "F.Mask" "F.Paste")
			(net "GND")
		)
	)
	(footprint ""
		(layer "F.Cu")
		(at 44.21378 -125.24486 -90)
		(property "Reference" "R1481"
			(at -0.3302 2.79781 90)
			(unlocked yes)
			(layer "F.SilkS")
			(effects
				(font
					(size 0.7874 0.5842)
					(thickness 0.1524)
				)
				(justify left)
			)
		)
		(property "Value" ""
			(at 0 0 270)
			(layer "F.Fab")
			(effects
				(font
					(size 1.27 1.27)
				)
			)
		)
		(duplicate_pad_numbers_are_jumpers no)
		(fp_line
			(start -4.18973 1.700022)
			(end 4.18973 1.700022)
			(stroke
				(width 0.1524)
				(type default)
			)
			(layer "F.SilkS")
		)
		(fp_line
			(start 4.18973 1.700022)
			(end 4.18973 -1.700022)
			(stroke
				(width 0.1524)
				(type default)
			)
			(layer "F.SilkS")
		)
		(fp_line
			(start -4.18973 -1.700022)
			(end -4.18973 1.700022)
			(stroke
				(width 0.1524)
				(type default)
			)
			(layer "F.SilkS")
		)
		(fp_line
			(start 4.18973 -1.700022)
			(end -4.18973 -1.700022)
			(stroke
				(width 0.1524)
				(type default)
			)
			(layer "F.SilkS")
		)
		(fp_line
			(start -3.24993 1.700022)
			(end 3.24993 1.700022)
			(stroke
				(width 0.1)
				(type default)
			)
			(layer "F.Fab")
		)
		(fp_line
			(start 3.24993 1.700022)
			(end 3.24993 -1.700022)
			(stroke
				(width 0.1)
				(type default)
			)
			(layer "F.Fab")
		)
		(fp_line
			(start -3.24993 -1.700022)
			(end -3.24993 1.700022)
			(stroke
				(width 0.1)
				(type default)
			)
			(layer "F.Fab")
		)
		(fp_line
			(start 3.24993 -1.700022)
			(end -3.24993 -1.700022)
			(stroke
				(width 0.1)
				(type default)
			)
			(layer "F.Fab")
		)
		(pad "1" smd rect
			(at -2.975102 0 270)
			(size 2.159 2.921)
			(layers "F.Cu" "F.Mask" "F.Paste")
			(net "P3V3_AUX")
		)
		(pad "2" smd rect
			(at 2.975102 0 270)
			(size 2.159 2.921)
			(layers "F.Cu" "F.Mask" "F.Paste")
			(net "P3V3_AUX_DSC")
		)
	)
)
